(kicad_pcb
	(version 20241229)
	(generator "pcbnew")
	(generator_version "9.0")
	(general
		(thickness 1.6)
		(legacy_teardrops no)
	)
	(paper "A4")
	(title_block
		(title "GMSL Deserializer")
		(date "2025-10-09")
		(rev "1.0.4")
		(company "Antmicro Ltd")
		(comment 1 "www.antmicro.com")
		(comment 9 "footprints 62-66 of 235")
	)
	(layers
		(0 "F.Cu" signal)
		(4 "In1.Cu" power)
		(6 "In2.Cu" power)
		(2 "B.Cu" signal)
		(9 "F.Adhes" user "F.Adhesive")
		(11 "B.Adhes" user "B.Adhesive")
		(13 "F.Paste" user)
		(15 "B.Paste" user)
		(5 "F.SilkS" user "F.Silkscreen")
		(7 "B.SilkS" user "B.Silkscreen")
		(1 "F.Mask" user)
		(3 "B.Mask" user)
		(17 "Dwgs.User" user "User.Drawings")
		(19 "Cmts.User" user "User.Comments")
		(21 "Eco1.User" user "User.Eco1")
		(23 "Eco2.User" user "User.Eco2")
		(25 "Edge.Cuts" user)
		(27 "Margin" user)
		(31 "F.CrtYd" user "F.Courtyard")
		(29 "B.CrtYd" user "B.Courtyard")
		(35 "F.Fab" user)
		(33 "B.Fab" user)
	)
	(footprint "antmicro-footprints:LED_0603_1608Metric_G"
		(layer "F.Cu")
		(at 158.496 96.1 90)
		(descr "LED SMD 0603 Green")
		(tags "LED SMD 0603 Green")
		(property "Reference" "D14"
			(at -1.916665 -40.079333 0)
			(layer "F.SilkS")
			(effects
				(font
					(size 0.7 0.7)
					(thickness 0.15)
				)
				(justify right bottom)
			)
		)
		(property "Value" "LED_G_0603_LTST-C190GKT"
			(at -0.001 1.599 90)
			(layer "F.Fab")
			(effects
				(font
					(size 0.7 0.7)
					(thickness 0.15)
				)
				(justify left bottom)
			)
		)
		(property "Datasheet" "https://media.digikey.com/pdf/Data%20Sheets/Lite-On%20PDFs/LTST-C190GKT.pdf"
			(at 0 0 90)
			(layer "F.Fab")
			(hide yes)
			(effects
				(font
					(size 1.27 1.27)
					(thickness 0.15)
				)
			)
		)
		(property "Description" "LED, Green, SMD, 0603, 20 mA, 2.1 V, 569 nm"
			(at 0 0 90)
			(layer "F.Fab")
			(hide yes)
			(effects
				(font
					(size 1.27 1.27)
					(thickness 0.15)
				)
			)
		)
		(property "Author" "Antmicro"
			(at 254.596 -62.396 0)
			(layer "F.Fab")
			(hide yes)
			(effects
				(font
					(size 1 1)
					(thickness 0.15)
				)
			)
		)
		(property "Color" "Green"
			(at 254.596 -62.396 0)
			(layer "F.Fab")
			(hide yes)
			(effects
				(font
					(size 1 1)
					(thickness 0.15)
				)
			)
		)
		(property "License" "Apache-2.0"
			(at 254.596 -62.396 0)
			(layer "F.Fab")
			(hide yes)
			(effects
				(font
					(size 1 1)
					(thickness 0.15)
				)
			)
		)
		(property "MPN" "LTST-C190GKT"
			(at 254.596 -62.396 0)
			(layer "F.Fab")
			(hide yes)
			(effects
				(font
					(size 1 1)
					(thickness 0.15)
				)
			)
		)
		(property "Manufacturer" "Lite-On"
			(at 254.596 -62.396 0)
			(layer "F.Fab")
			(hide yes)
			(effects
				(font
					(size 1 1)
					(thickness 0.15)
				)
			)
		)
		(property "VSD_class" "LED"
			(at 254.596 -62.396 0)
			(layer "F.Fab")
			(hide yes)
			(effects
				(font
					(size 1 1)
					(thickness 0.15)
				)
			)
		)
		(sheetname "/Connectors/")
		(sheetfile "connectors.kicad_sch")
		(attr smd)
		(fp_line
			(start 0.22 -0.35)
			(end -0.22 -0.35)
			(stroke
				(width 0.15)
				(type solid)
			)
			(layer "F.SilkS")
		)
		(fp_line
			(start -1.18 -0.319)
			(end -1.18 0.321)
			(stroke
				(width 0.15)
				(type solid)
			)
			(layer "F.SilkS")
		)
		(fp_line
			(start 0.105328 0.001008)
			(end 0.24 0.001)
			(stroke
				(width 0.1)
				(type solid)
			)
			(layer "F.SilkS")
		)
		(fp_line
			(start -0.094672 0.001008)
			(end 0.105328 -0.198992)
			(stroke
				(width 0.1)
				(type solid)
			)
			(layer "F.SilkS")
		)
		(fp_line
			(start -0.094672 0.001008)
			(end -0.24 0.001008)
			(stroke
				(width 0.1)
				(type solid)
			)
			(layer "F.SilkS")
		)
		(fp_line
			(start 0.105328 0.201008)
			(end 0.105328 -0.198992)
			(stroke
				(width 0.1)
				(type solid)
			)
			(layer "F.SilkS")
		)
		(fp_line
			(start 0.105328 0.201008)
			(end -0.094672 0.001008)
			(stroke
				(width 0.1)
				(type solid)
			)
			(layer "F.SilkS")
		)
		(fp_line
			(start -0.094672 0.201008)
			(end -0.094672 -0.198992)
			(stroke
				(width 0.1)
				(type solid)
			)
			(layer "F.SilkS")
		)
		(fp_line
			(start 0.22 0.35)
			(end -0.22 0.35)
			(stroke
				(width 0.15)
				(type solid)
			)
			(layer "F.SilkS")
		)
		(fp_rect
			(start 1.25 0.65)
			(end -1.25 -0.65)
			(stroke
				(width 0.05)
				(type solid)
			)
			(fill no)
			(layer "F.CrtYd")
		)
		(fp_line
			(start 0.201 -0.202)
			(end -0.101 0)
			(stroke
				(width 0.15)
				(type solid)
			)
			(layer "F.Fab")
		)
		(fp_line
			(start -0.199 -0.202)
			(end -0.199 0.1)
			(stroke
				(width 0.15)
				(type solid)
			)
			(layer "F.Fab")
		)
		(fp_line
			(start 0.599 0)
			(end 0.201 0)
			(stroke
				(width 0.15)
				(type solid)
			)
			(layer "F.Fab")
		)
		(fp_line
			(start 0.201 0)
			(end 0.201 -0.202)
			(stroke
				(width 0.15)
				(type solid)
			)
			(layer "F.Fab")
		)
		(fp_line
			(start -0.101 0)
			(end 0.201 0.2)
			(stroke
				(width 0.15)
				(type solid)
			)
			(layer "F.Fab")
		)
		(fp_line
			(start -0.199 0)
			(end -0.597 0)
			(stroke
				(width 0.15)
				(type solid)
			)
			(layer "F.Fab")
		)
		(fp_line
			(start 0.201 0.2)
			(end 0.201 0)
			(stroke
				(width 0.15)
				(type solid)
			)
			(layer "F.Fab")
		)
		(fp_line
			(start -0.199 0.2)
			(end -0.199 0.1)
			(stroke
				(width 0.15)
				(type solid)
			)
			(layer "F.Fab")
		)
		(fp_rect
			(start 0.848 0.4)
			(end -0.85 -0.402)
			(stroke
				(width 0.15)
				(type solid)
			)
			(fill no)
			(layer "F.Fab")
		)
		(pad "1" smd roundrect
			(at -0.7 0 270)
			(size 0.8 1)
			(layers "F.Cu" "F.Mask" "F.Paste")
			(roundrect_rratio 0.2)
			(net 111 "Net-(D14-C)")
			(pinfunction "C")
			(pintype "passive")
		)
		(pad "2" smd roundrect
			(at 0.7 0 270)
			(size 0.8 1)
			(layers "F.Cu" "F.Mask" "F.Paste")
			(roundrect_rratio 0.2)
			(net 110 "Net-(D14-A)")
			(pinfunction "A")
			(pintype "passive")
		)
	)
	(footprint "antmicro-footprints:R_0402_1005Metric"
		(layer "F.Cu")
		(at 154.178 74.676 45)
		(descr "Resistor SMD 0402")
		(tags "resistor SMD 0402")
		(property "Reference" "R46"
			(at 4.003639 0.193747 45)
			(layer "F.SilkS")
			(effects
				(font
					(size 0.7 0.7)
					(thickness 0.15)
				)
				(justify left bottom)
			)
		)
		(property "Value" "R_49R9_0402"
			(at -1.011843 1.772046 45)
			(layer "F.Fab")
			(effects
				(font
					(size 0.7 0.7)
					(thickness 0.15)
				)
				(justify left bottom)
			)
		)
		(property "Datasheet" "https://www.bourns.com/docs/product-datasheets/cr.pdf"
			(at 0 0 45)
			(layer "F.Fab")
			(hide yes)
			(effects
				(font
					(size 1.27 1.27)
					(thickness 0.15)
				)
			)
		)
		(property "Description" "SMD Chip Resistor, 49.9 ohm, ± 1%, 62.5 mW, 0402 [1005 Metric], Thick Film, General Purpose"
			(at 0 0 45)
			(layer "F.Fab")
			(hide yes)
			(effects
				(font
					(size 1.27 1.27)
					(thickness 0.15)
				)
			)
		)
		(property "Author" "Antmicro"
			(at 97.961596 -87.148215 0)
			(layer "F.Fab")
			(hide yes)
			(effects
				(font
					(size 1 1)
					(thickness 0.15)
				)
			)
		)
		(property "License" "Apache-2.0"
			(at 97.961596 -87.148215 0)
			(layer "F.Fab")
			(hide yes)
			(effects
				(font
					(size 1 1)
					(thickness 0.15)
				)
			)
		)
		(property "MPN" "CR0402-FX-49R9GLF"
			(at 97.961596 -87.148215 0)
			(layer "F.Fab")
			(hide yes)
			(effects
				(font
					(size 1 1)
					(thickness 0.15)
				)
			)
		)
		(property "Manufacturer" "Bourns"
			(at 97.961596 -87.148215 0)
			(layer "F.Fab")
			(hide yes)
			(effects
				(font
					(size 1 1)
					(thickness 0.15)
				)
			)
		)
		(property "Tolerance" "1%"
			(at 97.961596 -87.148215 0)
			(layer "F.Fab")
			(hide yes)
			(effects
				(font
					(size 1 1)
					(thickness 0.15)
				)
			)
		)
		(property "Val" "49R9"
			(at 97.961596 -87.148215 0)
			(layer "F.Fab")
			(hide yes)
			(effects
				(font
					(size 1 1)
					(thickness 0.15)
				)
			)
		)
		(sheetname "/Deserializer/")
		(sheetfile "deserializer.kicad_sch")
		(attr smd)
		(fp_poly
			(pts
				(xy -0.925 -0.47) (xy 0.925 -0.47) (xy 0.925 0.47) (xy -0.925 0.47)
			)
			(stroke
				(width 0.05)
				(type default)
			)
			(fill no)
			(layer "F.CrtYd")
		)
		(fp_poly
			(pts
				(xy -0.5 -0.25) (xy 0.5 -0.25) (xy 0.5 0.25) (xy -0.5 0.25)
			)
			(stroke
				(width 0.15)
				(type solid)
			)
			(fill no)
			(layer "F.Fab")
		)
		(pad "1" smd roundrect
			(at -0.48 0 45)
			(size 0.59 0.64)
			(layers "F.Cu" "F.Mask" "F.Paste")
			(roundrect_rratio 0.25)
			(net 25 "Net-(C35-Pad2)")
			(pintype "passive")
		)
		(pad "2" smd roundrect
			(at 0.48 0 45)
			(size 0.59 0.64)
			(layers "F.Cu" "F.Mask" "F.Paste")
			(roundrect_rratio 0.25)
			(net 1 "GND")
			(pintype "passive")
		)
	)
	(footprint "antmicro-footprints:R_0402_1005Metric"
		(layer "F.Cu")
		(at 181.356 68.144)
		(descr "Resistor SMD 0402")
		(tags "resistor SMD 0402")
		(property "Reference" "R10"
			(at -1.279 9.1482 0)
			(layer "F.SilkS")
			(effects
				(font
					(size 0.7 0.7)
					(thickness 0.15)
				)
				(justify left bottom)
			)
		)
		(property "Value" "R_100R_0402"
			(at -1.011843 1.772047 0)
			(layer "F.Fab")
			(effects
				(font
					(size 0.7 0.7)
					(thickness 0.15)
				)
				(justify left bottom)
			)
		)
		(property "Datasheet" "https://www.bourns.com/docs/product-datasheets/cr.pdf"
			(at 0 0 0)
			(layer "F.Fab")
			(hide yes)
			(effects
				(font
					(size 1.27 1.27)
					(thickness 0.15)
				)
			)
		)
		(property "Description" "SMD Chip Resistor, 100 ohm, ± 1%, 62.5 mW, 0402 [1005 Metric], Thick Film, General Purpose"
			(at 0 0 0)
			(layer "F.Fab")
			(hide yes)
			(effects
				(font
					(size 1.27 1.27)
					(thickness 0.15)
				)
			)
		)
		(property "Author" "Antmicro"
			(at 0 0 0)
			(layer "F.Fab")
			(hide yes)
			(effects
				(font
					(size 1 1)
					(thickness 0.15)
				)
			)
		)
		(property "License" "Apache-2.0"
			(at 0 0 0)
			(layer "F.Fab")
			(hide yes)
			(effects
				(font
					(size 1 1)
					(thickness 0.15)
				)
			)
		)
		(property "MPN" "CR0402-FX-1000GLF"
			(at 0 0 0)
			(layer "F.Fab")
			(hide yes)
			(effects
				(font
					(size 1 1)
					(thickness 0.15)
				)
			)
		)
		(property "Manufacturer" "Bourns"
			(at 0 0 0)
			(layer "F.Fab")
			(hide yes)
			(effects
				(font
					(size 1 1)
					(thickness 0.15)
				)
			)
		)
		(property "Tolerance" "1%"
			(at 0 0 0)
			(layer "F.Fab")
			(hide yes)
			(effects
				(font
					(size 1 1)
					(thickness 0.15)
				)
			)
		)
		(property "Val" "100R"
			(at 0 0 0)
			(layer "F.Fab")
			(hide yes)
			(effects
				(font
					(size 1 1)
					(thickness 0.15)
				)
			)
		)
		(sheetname "/Connectors/")
		(sheetfile "connectors.kicad_sch")
		(attr smd)
		(fp_rect
			(start -0.925 -0.47)
			(end 0.925 0.47)
			(stroke
				(width 0.05)
				(type default)
			)
			(fill no)
			(layer "F.CrtYd")
		)
		(fp_rect
			(start -0.5 -0.25)
			(end 0.5 0.25)
			(stroke
				(width 0.15)
				(type solid)
			)
			(fill no)
			(layer "F.Fab")
		)
		(pad "1" smd roundrect
			(at -0.48 0)
			(size 0.59 0.64)
			(layers "F.Cu" "F.Mask" "F.Paste")
			(roundrect_rratio 0.25)
			(net 66 "/Connectors/VSYNC_CAM1")
			(pintype "passive")
		)
		(pad "2" smd roundrect
			(at 0.48 0)
			(size 0.59 0.64)
			(layers "F.Cu" "F.Mask" "F.Paste")
			(roundrect_rratio 0.25)
			(net 37 "Net-(J6-Pad34)")
			(pintype "passive")
		)
	)
	(footprint "antmicro-footprints:R_0402_1005Metric"
		(layer "F.Cu")
		(at 181.356 66.04)
		(descr "Resistor SMD 0402")
		(tags "resistor SMD 0402")
		(property "Reference" "R13"
			(at -1.278 9.2202 0)
			(layer "F.SilkS")
			(effects
				(font
					(size 0.7 0.7)
					(thickness 0.15)
				)
				(justify left bottom)
			)
		)
		(property "Value" "R_100R_0402"
			(at -1.011843 1.772047 0)
			(layer "F.Fab")
			(effects
				(font
					(size 0.7 0.7)
					(thickness 0.15)
				)
				(justify left bottom)
			)
		)
		(property "Datasheet" "https://www.bourns.com/docs/product-datasheets/cr.pdf"
			(at 0 0 0)
			(layer "F.Fab")
			(hide yes)
			(effects
				(font
					(size 1.27 1.27)
					(thickness 0.15)
				)
			)
		)
		(property "Description" "SMD Chip Resistor, 100 ohm, ± 1%, 62.5 mW, 0402 [1005 Metric], Thick Film, General Purpose"
			(at 0 0 0)
			(layer "F.Fab")
			(hide yes)
			(effects
				(font
					(size 1.27 1.27)
					(thickness 0.15)
				)
			)
		)
		(property "Author" "Antmicro"
			(at 0 0 0)
			(layer "F.Fab")
			(hide yes)
			(effects
				(font
					(size 1 1)
					(thickness 0.15)
				)
			)
		)
		(property "License" "Apache-2.0"
			(at 0 0 0)
			(layer "F.Fab")
			(hide yes)
			(effects
				(font
					(size 1 1)
					(thickness 0.15)
				)
			)
		)
		(property "MPN" "CR0402-FX-1000GLF"
			(at 0 0 0)
			(layer "F.Fab")
			(hide yes)
			(effects
				(font
					(size 1 1)
					(thickness 0.15)
				)
			)
		)
		(property "Manufacturer" "Bourns"
			(at 0 0 0)
			(layer "F.Fab")
			(hide yes)
			(effects
				(font
					(size 1 1)
					(thickness 0.15)
				)
			)
		)
		(property "Tolerance" "1%"
			(at 0 0 0)
			(layer "F.Fab")
			(hide yes)
			(effects
				(font
					(size 1 1)
					(thickness 0.15)
				)
			)
		)
		(property "Val" "100R"
			(at 0 0 0)
			(layer "F.Fab")
			(hide yes)
			(effects
				(font
					(size 1 1)
					(thickness 0.15)
				)
			)
		)
		(sheetname "/Connectors/")
		(sheetfile "connectors.kicad_sch")
		(attr smd)
		(fp_rect
			(start -0.925 -0.47)
			(end 0.925 0.47)
			(stroke
				(width 0.05)
				(type default)
			)
			(fill no)
			(layer "F.CrtYd")
		)
		(fp_rect
			(start -0.5 -0.25)
			(end 0.5 0.25)
			(stroke
				(width 0.15)
				(type solid)
			)
			(fill no)
			(layer "F.Fab")
		)
		(pad "1" smd roundrect
			(at -0.48 0)
			(size 0.59 0.64)
			(layers "F.Cu" "F.Mask" "F.Paste")
			(roundrect_rratio 0.25)
			(net 45 "/Connectors/SCL_CAM")
			(pintype "passive")
		)
		(pad "2" smd roundrect
			(at 0.48 0)
			(size 0.59 0.64)
			(layers "F.Cu" "F.Mask" "F.Paste")
			(roundrect_rratio 0.25)
			(net 120 "/Connectors/SCL_CAM0")
			(pintype "passive")
		)
	)
	(footprint "antmicro-footprints:Conn_FAKRA_7-2287906-0"
		(layer "F.Cu")
		(at 129.286 38.348)
		(descr "Connector FAKRA, 5 pins")
		(property "Reference" "J2"
			(at 5.054 5.3 0)
			(layer "F.SilkS")
			(effects
				(font
					(size 0.7 0.7)
					(thickness 0.15)
				)
				(justify left bottom)
			)
		)
		(property "Value" "Conn_FAKRA_59S2AQ-40MT5-Z_1"
			(at -6.55 15.019 0)
			(layer "F.Fab")
			(effects
				(font
					(size 0.7 0.7)
					(thickness 0.15)
				)
				(justify left bottom)
			)
		)
		(property ki_fp_filters "*BNC* *SMA* *SMB* *SMC* *Cinch*")
		(sheetname "/Connectors/")
		(sheetfile "connectors.kicad_sch")
		(attr through_hole)
		(fp_line
			(start -4.572 0.94)
			(end -4.572 13.919)
			(stroke
				(width 0.15)
				(type solid)
			)
			(layer "F.SilkS")
		)
		(fp_line
			(start -4.572 13.919)
			(end 4.572 13.919)
			(stroke
				(width 0.15)
				(type solid)
			)
			(layer "F.SilkS")
		)
		(fp_line
			(start 4.572 0.94)
			(end -4.572 0.94)
			(stroke
				(width 0.15)
				(type solid)
			)
			(layer "F.SilkS")
		)
		(fp_line
			(start 4.572 13.919)
			(end 4.572 0.94)
			(stroke
				(width 0.15)
				(type solid)
			)
			(layer "F.SilkS")
		)
		(fp_rect
			(start -5.14 -12.64)
			(end 5.131 14.164)
			(stroke
				(width 0.05)
				(type solid)
			)
			(fill no)
			(layer "F.CrtYd")
		)
		(fp_text user "${REFERENCE}"
			(at -6.55 18.619 0)
			(layer "F.Fab")
			(effects
				(font
					(size 0.7 0.7)
					(thickness 0.15)
				)
				(justify left bottom)
			)
		)
		(fp_text user "License: Apache-2.0"
			(at -6.55 16.219 0)
			(layer "F.Fab")
			(effects
				(font
					(size 0.7 0.7)
					(thickness 0.15)
				)
				(justify left bottom)
			)
		)
		(fp_text user "Author: Antmicro"
			(at -6.55 17.419 0)
			(layer "F.Fab")
			(effects
				(font
					(size 0.7 0.7)
					(thickness 0.15)
				)
				(justify left bottom)
			)
		)
		(pad "1" smd roundrect
			(at 0 3.62 270)
			(size 4.79 1.9)
			(layers "F.Cu" "F.Mask" "F.Paste")
			(roundrect_rratio 0.25)
			(net 114 "/Connectors/PoCA")
			(pinfunction "1")
			(pintype "passive")
		)
		(pad "2" thru_hole circle
			(at -3 3.315 270)
			(size 1.8 1.8)
			(drill 1.45)
			(layers "*.Cu" "*.Mask")
			(remove_unused_layers no)
			(net 1 "GND")
			(pinfunction "2")
			(pintype "passive")
		)
		(pad "2" smd roundrect
			(at -2.9975 3.7175 270)
			(size 4.985 1.8)
			(layers "F.Cu" "F.Mask" "F.Paste")
			(roundrect_rratio 0.25)
			(net 1 "GND")
			(pinfunction "2")
			(pintype "passive")
		)
		(pad "3" thru_hole circle
			(at -3 10.315 270)
			(size 1.8 1.8)
			(drill 1.45)
			(layers "*.Cu" "*.Mask")
			(remove_unused_layers no)
			(net 1 "GND")
			(pinfunction "3")
			(pintype "passive")
		)
		(pad "3" smd roundrect
			(at -3 10.815 270)
			(size 5.6 1.8)
			(layers "F.Cu" "F.Mask" "F.Paste")
			(roundrect_rratio 0.25)
			(net 1 "GND")
			(pinfunction "3")
			(pintype "passive")
		)
		(pad "4" thru_hole circle
			(at 3 10.315 270)
			(size 1.8 1.8)
			(drill 1.45)
			(layers "*.Cu" "*.Mask")
			(remove_unused_layers no)
			(net 1 "GND")
			(pinfunction "4")
			(pintype "passive")
		)
		(pad "4" smd roundrect
			(at 3 10.815 270)
			(size 5.6 1.8)
			(layers "F.Cu" "F.Mask" "F.Paste")
			(roundrect_rratio 0.25)
			(net 1 "GND")
			(pinfunction "4")
			(pintype "passive")
		)
		(pad "5" thru_hole circle
			(at 3 3.315 270)
			(size 1.8 1.8)
			(drill 1.45)
			(layers "*.Cu" "*.Mask")
			(remove_unused_layers no)
			(net 1 "GND")
			(pinfunction "5")
			(pintype "passive")
		)
		(pad "5" smd roundrect
			(at 3 3.72 270)
			(size 4.99 1.8)
			(layers "F.Cu" "F.Mask" "F.Paste")
			(roundrect_rratio 0.25)
			(net 1 "GND")
			(pinfunction "5")
			(pintype "passive")
		)
	)
)
